(kicad_pcb
	(version 20240108)
	(generator "pcbnew")
	(generator_version "8.0")
	(general
		(thickness 1.62)
		(legacy_teardrops no)
	)
	(paper "A4")
	(title_block
		(title "Jetson Orin Baseboard")
		(date "2025-03-12")
		(rev "1.3.4")
		(company "Antmicro Ltd")
		(comment 1 "www.antmicro.com")
		(comment 9 "footprints 153-156 of 677")
	)
	(layers
		(0 "F.Cu" signal)
		(1 "In1.Cu" signal)
		(2 "In2.Cu" signal)
		(3 "In3.Cu" signal)
		(4 "In4.Cu" jumper)
		(5 "In5.Cu" signal)
		(6 "In6.Cu" signal)
		(31 "B.Cu" signal)
		(32 "B.Adhes" user "B.Adhesive")
		(33 "F.Adhes" user "F.Adhesive")
		(34 "B.Paste" user)
		(35 "F.Paste" user)
		(36 "B.SilkS" user "B.Silkscreen")
		(37 "F.SilkS" user "F.Silkscreen")
		(38 "B.Mask" user)
		(39 "F.Mask" user)
		(40 "Dwgs.User" user "User.Drawings")
		(41 "Cmts.User" user "User.Comments")
		(42 "Eco1.User" user "User.Eco1")
		(43 "Eco2.User" user "User.Eco2")
		(44 "Edge.Cuts" user)
		(45 "Margin" user)
		(46 "B.CrtYd" user "B.Courtyard")
		(47 "F.CrtYd" user "F.Courtyard")
		(48 "B.Fab" user)
		(49 "F.Fab" user)
	)
	(footprint "antmicro-footprints:C_0402_1005Metric"
		(layer "F.Cu")
		(at 81.9 108 180)
		(descr "Capacitor SMD 0402")
		(tags "capacitor SMD 0402")
		(property "Reference" "C140"
			(at -0.85 -0.45 180)
			(layer "F.SilkS")
			(effects
				(font
					(size 0.7 0.7)
					(thickness 0.15)
				)
				(justify left bottom)
			)
		)
		(property "Value" "C_100n_0402"
			(at 0 1.4 180)
			(layer "F.Fab")
			(effects
				(font
					(size 0.7 0.7)
					(thickness 0.15)
				)
				(justify left bottom)
			)
		)
		(property "Footprint" "antmicro-footprints:C_0402_1005Metric"
			(at 0 0 180)
			(layer "F.Fab")
			(hide yes)
			(effects
				(font
					(size 1.27 1.27)
					(thickness 0.15)
				)
			)
		)
		(property "Datasheet" "https://www.murata.com/products/productdetail?partno=GRM155R61H104KE14%23"
			(at 0 0 180)
			(layer "F.Fab")
			(hide yes)
			(effects
				(font
					(size 1.27 1.27)
					(thickness 0.15)
				)
			)
		)
		(property "Author" "Antmicro"
			(at 163.8 216 0)
			(layer "F.Fab")
			(hide yes)
			(effects
				(font
					(size 1 1)
					(thickness 0.15)
				)
			)
		)
		(property "Dielectric" "X5R"
			(at 163.8 216 0)
			(layer "F.Fab")
			(hide yes)
			(effects
				(font
					(size 1 1)
					(thickness 0.15)
				)
			)
		)
		(property "License" "Apache-2.0"
			(at 163.8 216 0)
			(layer "F.Fab")
			(hide yes)
			(effects
				(font
					(size 1 1)
					(thickness 0.15)
				)
			)
		)
		(property "MPN" "GRM155R61H104KE14D"
			(at 163.8 216 0)
			(layer "F.Fab")
			(hide yes)
			(effects
				(font
					(size 1 1)
					(thickness 0.15)
				)
			)
		)
		(property "Manufacturer" "Murata"
			(at 163.8 216 0)
			(layer "F.Fab")
			(hide yes)
			(effects
				(font
					(size 1 1)
					(thickness 0.15)
				)
			)
		)
		(property "Val" "100n"
			(at 163.8 216 0)
			(layer "F.Fab")
			(hide yes)
			(effects
				(font
					(size 1 1)
					(thickness 0.15)
				)
			)
		)
		(property "Voltage" "50V"
			(at 163.8 216 0)
			(layer "F.Fab")
			(hide yes)
			(effects
				(font
					(size 1 1)
					(thickness 0.15)
				)
			)
		)
		(sheetname "USB Debug, DP")
		(sheetfile "usb.kicad_sch")
		(attr smd)
		(fp_rect
			(start -0.925 -0.47)
			(end 0.925 0.47)
			(stroke
				(width 0.05)
				(type default)
			)
			(fill none)
			(layer "F.CrtYd")
		)
		(fp_line
			(start 0.504 0.248)
			(end -0.494 0.248)
			(stroke
				(width 0.15)
				(type solid)
			)
			(layer "F.Fab")
		)
		(fp_line
			(start 0.504 -0.25)
			(end 0.504 0.248)
			(stroke
				(width 0.15)
				(type solid)
			)
			(layer "F.Fab")
		)
		(fp_line
			(start -0.494 0.248)
			(end -0.494 -0.25)
			(stroke
				(width 0.15)
				(type solid)
			)
			(layer "F.Fab")
		)
		(fp_line
			(start -0.494 -0.25)
			(end 0.504 -0.25)
			(stroke
				(width 0.15)
				(type solid)
			)
			(layer "F.Fab")
		)
		(fp_text user "${REFERENCE}"
			(at -0.932 3.168 180)
			(layer "F.Fab")
			(hide yes)
			(effects
				(font
					(size 0.7 0.7)
					(thickness 0.15)
				)
				(justify left bottom)
			)
		)
		(fp_text user "License: Apache-2.0"
			(at -0.932 5.17 180)
			(layer "F.Fab")
			(hide yes)
			(effects
				(font
					(size 0.7 0.7)
					(thickness 0.15)
				)
				(justify left bottom)
			)
		)
		(fp_text user "Author: Antmicro"
			(at -0.932 4.17 180)
			(layer "F.Fab")
			(hide yes)
			(effects
				(font
					(size 0.7 0.7)
					(thickness 0.15)
				)
				(justify left bottom)
			)
		)
		(pad "1" smd roundrect
			(at -0.48 0 180)
			(size 0.59 0.64)
			(layers "F.Cu" "F.Paste" "F.Mask")
			(roundrect_rratio 0.25)
			(net 58 "USBSS0_RX_P")
			(pintype "passive")
		)
		(pad "2" smd roundrect
			(at 0.48 0 180)
			(size 0.59 0.64)
			(layers "F.Cu" "F.Paste" "F.Mask")
			(roundrect_rratio 0.25)
			(net 186 "/USB Debug, DP/USBSS0_RX_C_N")
			(pintype "passive")
		)
	)
	(footprint "antmicro-footprints:XDFN-2_1x0.60mm"
		(layer "F.Cu")
		(at 137.8 86.07 90)
		(property "Reference" "D41"
			(at -0.3 0.4 0)
			(layer "F.SilkS")
			(effects
				(font
					(size 0.7 0.7)
					(thickness 0.15)
				)
				(justify left bottom)
			)
		)
		(property "Value" "TPD1E0B04_XDFN-2"
			(at 0 1.5 90)
			(layer "F.Fab")
			(effects
				(font
					(size 0.7 0.7)
					(thickness 0.15)
				)
				(justify left bottom)
			)
		)
		(property "Footprint" "antmicro-footprints:XDFN-2_1x0.60mm"
			(at 0 0 90)
			(layer "F.Fab")
			(hide yes)
			(effects
				(font
					(size 1.27 1.27)
					(thickness 0.15)
				)
			)
		)
		(property "Datasheet" "https://www.ti.com/general/docs/suppproductinfo.tsp?distId=26&gotoUrl=https://www.ti.com/lit/gpn/tpd1e0b04"
			(at 0 0 90)
			(layer "F.Fab")
			(hide yes)
			(effects
				(font
					(size 1.27 1.27)
					(thickness 0.15)
				)
			)
		)
		(property "MPN" "TPD1E0B04DPYR"
			(at 223.87 -51.73 0)
			(layer "F.Fab")
			(hide yes)
			(effects
				(font
					(size 1 1)
					(thickness 0.15)
				)
			)
		)
		(property "Manufacturer" "Texas Instruments"
			(at 223.87 -51.73 0)
			(layer "F.Fab")
			(hide yes)
			(effects
				(font
					(size 1 1)
					(thickness 0.15)
				)
			)
		)
		(property "Author" "Antmicro"
			(at 223.87 -51.73 0)
			(layer "F.Fab")
			(hide yes)
			(effects
				(font
					(size 1 1)
					(thickness 0.15)
				)
			)
		)
		(property "License" "Apache-2.0"
			(at 223.87 -51.73 0)
			(layer "F.Fab")
			(hide yes)
			(effects
				(font
					(size 1 1)
					(thickness 0.15)
				)
			)
		)
		(sheetname "Peripherals")
		(sheetfile "peripherals.kicad_sch")
		(attr smd)
		(fp_rect
			(start -0.725 -0.475)
			(end 0.725 0.475)
			(stroke
				(width 0.05)
				(type solid)
			)
			(fill none)
			(layer "F.CrtYd")
		)
		(fp_rect
			(start -0.55 -0.35)
			(end 0.55 0.35)
			(stroke
				(width 0.15)
				(type solid)
			)
			(fill none)
			(layer "F.Fab")
		)
		(fp_text user "License: Apache-2.0"
			(at -0.8 5.6 90)
			(layer "F.Fab")
			(hide yes)
			(effects
				(font
					(size 0.7 0.7)
					(thickness 0.15)
				)
				(justify left bottom)
			)
		)
		(fp_text user "Author: Antmicro"
			(at -0.8 4.4 90)
			(layer "F.Fab")
			(hide yes)
			(effects
				(font
					(size 0.7 0.7)
					(thickness 0.15)
				)
				(justify left bottom)
			)
		)
		(fp_text user "${REFERENCE}"
			(at -0.8 3.2 90)
			(layer "F.Fab")
			(hide yes)
			(effects
				(font
					(size 0.7 0.7)
					(thickness 0.15)
				)
				(justify left bottom)
			)
		)
		(pad "1" smd roundrect
			(at -0.351 0 90)
			(size 0.3 0.5)
			(layers "F.Cu" "F.Paste" "F.Mask")
			(roundrect_rratio 0.25)
			(net 411 "/Peripherals/PCIE2_TX0_CONN_N")
			(pinfunction "C")
			(pintype "passive")
		)
		(pad "2" smd roundrect
			(at 0.349 0 90)
			(size 0.3 0.5)
			(layers "F.Cu" "F.Paste" "F.Mask")
			(roundrect_rratio 0.25)
			(net 1 "GND")
			(pinfunction "A")
			(pintype "passive")
		)
	)
	(footprint "antmicro-footprints:LED_0603_1608Metric_G"
		(layer "F.Cu")
		(at 129.1 101.95 -90)
		(descr "LED SMD 0603 Green")
		(tags "LED SMD 0603 Green")
		(property "Reference" "D51"
			(at -3.4 -0.4 90)
			(layer "F.SilkS")
			(effects
				(font
					(size 0.7 0.7)
					(thickness 0.15)
				)
				(justify right bottom)
			)
		)
		(property "Value" "LED_G_0603_LTST-C190GKT"
			(at -0.001 1.599 90)
			(layer "F.Fab")
			(effects
				(font
					(size 0.7 0.7)
					(thickness 0.15)
				)
				(justify right bottom)
			)
		)
		(property "Footprint" "antmicro-footprints:LED_0603_1608Metric_G"
			(at 0 0 -90)
			(layer "F.Fab")
			(hide yes)
			(effects
				(font
					(size 1.27 1.27)
					(thickness 0.15)
				)
			)
		)
		(property "Datasheet" "https://media.digikey.com/pdf/Data%20Sheets/Lite-On%20PDFs/LTST-C190GKT.pdf"
			(at 0 0 -90)
			(layer "F.Fab")
			(hide yes)
			(effects
				(font
					(size 1.27 1.27)
					(thickness 0.15)
				)
			)
		)
		(property "Author" "Antmicro"
			(at 27.15 231.05 0)
			(layer "F.Fab")
			(hide yes)
			(effects
				(font
					(size 1 1)
					(thickness 0.15)
				)
			)
		)
		(property "Color" "Green"
			(at 27.15 231.05 0)
			(layer "F.Fab")
			(hide yes)
			(effects
				(font
					(size 1 1)
					(thickness 0.15)
				)
			)
		)
		(property "License" "Apache-2.0"
			(at 27.15 231.05 0)
			(layer "F.Fab")
			(hide yes)
			(effects
				(font
					(size 1 1)
					(thickness 0.15)
				)
			)
		)
		(property "MPN" "LTST-C190GKT"
			(at 27.15 231.05 0)
			(layer "F.Fab")
			(hide yes)
			(effects
				(font
					(size 1 1)
					(thickness 0.15)
				)
			)
		)
		(property "Manufacturer" "Lite-On"
			(at 27.15 231.05 0)
			(layer "F.Fab")
			(hide yes)
			(effects
				(font
					(size 1 1)
					(thickness 0.15)
				)
			)
		)
		(sheetname "M.2")
		(sheetfile "m-2.kicad_sch")
		(attr smd)
		(fp_line
			(start 0.22 0.35)
			(end -0.22 0.35)
			(stroke
				(width 0.15)
				(type solid)
			)
			(layer "F.SilkS")
		)
		(fp_line
			(start -0.094672 0.201008)
			(end -0.094672 -0.198992)
			(stroke
				(width 0.1)
				(type solid)
			)
			(layer "F.SilkS")
		)
		(fp_line
			(start 0.105328 0.201008)
			(end -0.094672 0.001008)
			(stroke
				(width 0.1)
				(type solid)
			)
			(layer "F.SilkS")
		)
		(fp_line
			(start 0.105328 0.201008)
			(end 0.105328 -0.198992)
			(stroke
				(width 0.1)
				(type solid)
			)
			(layer "F.SilkS")
		)
		(fp_line
			(start -0.094672 0.001008)
			(end -0.24 0.001008)
			(stroke
				(width 0.1)
				(type solid)
			)
			(layer "F.SilkS")
		)
		(fp_line
			(start -0.094672 0.001008)
			(end 0.105328 -0.198992)
			(stroke
				(width 0.1)
				(type solid)
			)
			(layer "F.SilkS")
		)
		(fp_line
			(start 0.105328 0.001008)
			(end 0.24 0.001)
			(stroke
				(width 0.1)
				(type solid)
			)
			(layer "F.SilkS")
		)
		(fp_line
			(start -1.18 -0.319)
			(end -1.18 0.321)
			(stroke
				(width 0.15)
				(type solid)
			)
			(layer "F.SilkS")
		)
		(fp_line
			(start 0.22 -0.35)
			(end -0.22 -0.35)
			(stroke
				(width 0.15)
				(type solid)
			)
			(layer "F.SilkS")
		)
		(fp_rect
			(start 1.25 0.65)
			(end -1.25 -0.65)
			(stroke
				(width 0.05)
				(type solid)
			)
			(fill none)
			(layer "F.CrtYd")
		)
		(fp_line
			(start -0.199 0.2)
			(end -0.199 0.1)
			(stroke
				(width 0.15)
				(type solid)
			)
			(layer "F.Fab")
		)
		(fp_line
			(start 0.201 0.2)
			(end 0.201 0)
			(stroke
				(width 0.15)
				(type solid)
			)
			(layer "F.Fab")
		)
		(fp_line
			(start -0.199 0)
			(end -0.597 0)
			(stroke
				(width 0.15)
				(type solid)
			)
			(layer "F.Fab")
		)
		(fp_line
			(start -0.101 0)
			(end 0.201 0.2)
			(stroke
				(width 0.15)
				(type solid)
			)
			(layer "F.Fab")
		)
		(fp_line
			(start 0.201 0)
			(end 0.201 -0.202)
			(stroke
				(width 0.15)
				(type solid)
			)
			(layer "F.Fab")
		)
		(fp_line
			(start 0.599 0)
			(end 0.201 0)
			(stroke
				(width 0.15)
				(type solid)
			)
			(layer "F.Fab")
		)
		(fp_line
			(start -0.199 -0.202)
			(end -0.199 0.1)
			(stroke
				(width 0.15)
				(type solid)
			)
			(layer "F.Fab")
		)
		(fp_line
			(start 0.201 -0.202)
			(end -0.101 0)
			(stroke
				(width 0.15)
				(type solid)
			)
			(layer "F.Fab")
		)
		(fp_rect
			(start 0.848 0.4)
			(end -0.85 -0.402)
			(stroke
				(width 0.15)
				(type solid)
			)
			(fill none)
			(layer "F.Fab")
		)
		(fp_text user "${REFERENCE}"
			(at -1.4224 5.999 90)
			(layer "F.Fab")
			(hide yes)
			(effects
				(font
					(size 0.7 0.7)
					(thickness 0.15)
				)
				(justify right bottom)
			)
		)
		(fp_text user "Author: Antmicro"
			(at -1.4224 4.799 90)
			(layer "F.Fab")
			(hide yes)
			(effects
				(font
					(size 0.7 0.7)
					(thickness 0.15)
				)
				(justify right bottom)
			)
		)
		(fp_text user "License: Apache-2.0"
			(at -1.4224 3.599 90)
			(layer "F.Fab")
			(hide yes)
			(effects
				(font
					(size 0.7 0.7)
					(thickness 0.15)
				)
				(justify right bottom)
			)
		)
		(pad "1" smd roundrect
			(at -0.7 0 90)
			(size 0.8 1)
			(layers "F.Cu" "F.Paste" "F.Mask")
			(roundrect_rratio 0.2)
			(net 169 "/M.2/~{LED1}")
			(pinfunction "C")
			(pintype "passive")
		)
		(pad "2" smd roundrect
			(at 0.7 0 90)
			(size 0.8 1)
			(layers "F.Cu" "F.Paste" "F.Mask")
			(roundrect_rratio 0.2)
			(net 184 "Net-(D51-A)")
			(pinfunction "A")
			(pintype "passive")
		)
	)
	(footprint "antmicro-footprints:C_0603_1608Metric_EIA"
		(layer "F.Cu")
		(at 55.28 94.63 90)
		(descr "Capacitor SMD 0603, IPC-7351 Density Level A")
		(tags "Capacitor 0603")
		(property "Reference" "C103"
			(at -2.32 28.32 90)
			(layer "F.SilkS")
			(effects
				(font
					(size 0.7 0.7)
					(thickness 0.15)
				)
				(justify left bottom)
			)
		)
		(property "Value" "C_22u_16V_0603"
			(at -1.42757 1.770288 90)
			(layer "F.Fab")
			(effects
				(font
					(size 0.7 0.7)
					(thickness 0.15)
				)
				(justify left bottom)
			)
		)
		(property "Footprint" "antmicro-footprints:C_0603_1608Metric_EIA"
			(at 0 0 90)
			(layer "F.Fab")
			(hide yes)
			(effects
				(font
					(size 1.27 1.27)
					(thickness 0.15)
				)
			)
		)
		(property "Datasheet" "https://product.samsungsem.com/mlcc/CL10A226MO7JZN.do"
			(at 0 0 90)
			(layer "F.Fab")
			(hide yes)
			(effects
				(font
					(size 1.27 1.27)
					(thickness 0.15)
				)
			)
		)
		(property "Description" "SMD Multilayer Ceramic Capacitor"
			(at 0 0 90)
			(layer "F.Fab")
			(hide yes)
			(effects
				(font
					(size 1.27 1.27)
					(thickness 0.15)
				)
			)
		)
		(property "Manufacturer" "Samsung Electro-Mechanics"
			(at 0 0 90)
			(unlocked yes)
			(layer "F.Fab")
			(hide yes)
			(effects
				(font
					(size 1 1)
					(thickness 0.15)
				)
			)
		)
		(property "MPN" "CL10A226MO7JZNC"
			(at 0 0 90)
			(unlocked yes)
			(layer "F.Fab")
			(hide yes)
			(effects
				(font
					(size 1 1)
					(thickness 0.15)
				)
			)
		)
		(property "Val" "22u"
			(at 0 0 90)
			(unlocked yes)
			(layer "F.Fab")
			(hide yes)
			(effects
				(font
					(size 1 1)
					(thickness 0.15)
				)
			)
		)
		(property "License" "Apache-2.0"
			(at 0 0 90)
			(unlocked yes)
			(layer "F.Fab")
			(hide yes)
			(effects
				(font
					(size 1 1)
					(thickness 0.15)
				)
			)
		)
		(property "Author" "Antmicro"
			(at 0 0 90)
			(unlocked yes)
			(layer "F.Fab")
			(hide yes)
			(effects
				(font
					(size 1 1)
					(thickness 0.15)
				)
			)
		)
		(property "Voltage" "16V"
			(at 0 0 90)
			(unlocked yes)
			(layer "F.Fab")
			(hide yes)
			(effects
				(font
					(size 1 1)
					(thickness 0.15)
				)
			)
		)
		(property "Dielectric" ""
			(at 0 0 90)
			(unlocked yes)
			(layer "F.Fab")
			(hide yes)
			(effects
				(font
					(size 1 1)
					(thickness 0.15)
				)
			)
		)
		(sheetname "Supply")
		(sheetfile "supply.kicad_sch")
		(attr smd)
		(fp_line
			(start -0.15 -0.55)
			(end 0.15 -0.55)
			(stroke
				(width 0.15)
				(type solid)
			)
			(layer "F.SilkS")
		)
		(fp_line
			(start -0.15 0.55)
			(end 0.15 0.55)
			(stroke
				(width 0.15)
				(type solid)
			)
			(layer "F.SilkS")
		)
		(fp_rect
			(start -1.25 -0.65)
			(end 1.25 0.65)
			(stroke
				(width 0.05)
				(type solid)
			)
			(fill none)
			(layer "F.CrtYd")
		)
		(fp_rect
			(start -0.8 -0.45)
			(end 0.8 0.45)
			(stroke
				(width 0.15)
				(type solid)
			)
			(fill none)
			(layer "F.Fab")
		)
		(fp_text user "License: Apache-2.0"
			(at -1.682 5.895 90)
			(layer "F.Fab")
			(hide yes)
			(effects
				(font
					(size 0.7 0.7)
					(thickness 0.15)
				)
				(justify left bottom)
			)
		)
		(fp_text user "Author: Antmicro"
			(at -1.682 4.894 90)
			(layer "F.Fab")
			(hide yes)
			(effects
				(font
					(size 0.7 0.7)
					(thickness 0.15)
				)
				(justify left bottom)
			)
		)
		(fp_text user "${REFERENCE}"
			(at -1.682 3.895 90)
			(layer "F.Fab")
			(hide yes)
			(effects
				(font
					(size 0.7 0.7)
					(thickness 0.15)
				)
				(justify left bottom)
			)
		)
		(pad "1" smd roundrect
			(at -0.7 0 90)
			(size 0.8 1.1)
			(layers "F.Cu" "F.Paste" "F.Mask")
			(roundrect_rratio 0.2)
			(net 1 "GND")
			(pintype "passive")
		)
		(pad "2" smd roundrect
			(at 0.7 0 90)
			(size 0.8 1.1)
			(layers "F.Cu" "F.Paste" "F.Mask")
			(roundrect_rratio 0.2)
			(net 761 "/Supply/5V_OUT")
			(pintype "passive")
		)
	)
)
